(kicad_pcb
	(version 20260206)
	(generator "pcbnew")
	(generator_version "10.0")
	(general
		(thickness 1.6)
		(legacy_teardrops no)
	)
	(paper "A4")
	(title_block
		(title "03242023_DA0F0TMBIJ0_F0T_Motherboard_J_brd_V01_OCP.brd")
		(comment 1 "Grand Teton / footprints 1645-1651 of 6105")
	)
	(layers
		(0 "F.Cu" signal "TOP")
		(4 "In1.Cu" signal "GND")
		(6 "In2.Cu" signal "IN1")
		(8 "In3.Cu" signal "GND1")
		(10 "In4.Cu" signal "IN2")
		(12 "In5.Cu" signal "GND2")
		(14 "In6.Cu" signal "IN3")
		(16 "In7.Cu" signal "GND3")
		(18 "In8.Cu" signal "VCC")
		(20 "In9.Cu" signal "VCC1")
		(22 "In10.Cu" signal "GND4")
		(24 "In11.Cu" signal "IN4")
		(26 "In12.Cu" signal "GND5")
		(28 "In13.Cu" signal "IN5")
		(30 "In14.Cu" signal "GND6")
		(32 "In15.Cu" signal "IN6")
		(34 "In16.Cu" signal "GND7")
		(2 "B.Cu" signal "BOTTOM")
		(9 "F.Adhes" user "F.Adhesive")
		(11 "B.Adhes" user "B.Adhesive")
		(13 "F.Paste" user "Package Geometry/Pastemask Top")
		(15 "B.Paste" user "Package Geometry/Pastemask Bottom")
		(5 "F.SilkS" user "Ref Des/Silkscreen Top")
		(7 "B.SilkS" user "Ref Des/Silkscreen Bottom")
		(1 "F.Mask" user "Board Geometry/Soldermask Top")
		(3 "B.Mask" user "Board Geometry/Soldermask Bottom")
		(17 "Dwgs.User" user "User.Drawings")
		(19 "Cmts.User" user "User.Comments")
		(21 "Eco1.User" user "User.Eco1")
		(23 "Eco2.User" user "User.Eco2")
		(25 "Edge.Cuts" user "Board Geometry/Outline")
		(27 "Margin" user)
		(31 "F.CrtYd" user "Package Geometry/Place Bound Top")
		(29 "B.CrtYd" user "Package Geometry/Place Bound Bottom")
		(35 "F.Fab" user "Ref Des/Assembly Top")
		(33 "B.Fab" user "Ref Des/Assembly Bottom")
	)
	(footprint ""
		(layer "F.Cu")
		(at 172.8724 -94.338648 90)
		(property "Reference" "R4581"
			(at 0 0 90)
			(layer "F.SilkS")
			(hide yes)
			(effects
				(font
					(size 1.27 1.27)
				)
			)
		)
		(property "Value" ""
			(at 0 0 90)
			(layer "F.Fab")
			(effects
				(font
					(size 1.27 1.27)
				)
			)
		)
		(duplicate_pad_numbers_are_jumpers no)
		(fp_line
			(start 0.7874 -0.4064)
			(end 0.7874 0.4064)
			(stroke
				(width 0.1524)
				(type default)
			)
			(layer "F.SilkS")
		)
		(fp_line
			(start -0.7874 -0.4064)
			(end 0.7874 -0.4064)
			(stroke
				(width 0.1524)
				(type default)
			)
			(layer "F.SilkS")
		)
		(fp_line
			(start 0.7874 0.4064)
			(end -0.7874 0.4064)
			(stroke
				(width 0.1524)
				(type default)
			)
			(layer "F.SilkS")
		)
		(fp_line
			(start -0.7874 0.4064)
			(end -0.7874 -0.4064)
			(stroke
				(width 0.1524)
				(type default)
			)
			(layer "F.SilkS")
		)
		(fp_line
			(start -0.12065 -0.305054)
			(end -0.12065 -0.2794)
			(stroke
				(width 0.1)
				(type default)
			)
			(layer "F.Fab")
		)
		(fp_line
			(start -0.67945 -0.305054)
			(end -0.12065 -0.305054)
			(stroke
				(width 0.1)
				(type default)
			)
			(layer "F.Fab")
		)
		(fp_line
			(start 0.67945 -0.3048)
			(end 0.67945 0.3048)
			(stroke
				(width 0.1)
				(type default)
			)
			(layer "F.Fab")
		)
		(fp_line
			(start 0.12065 -0.3048)
			(end 0.67945 -0.3048)
			(stroke
				(width 0.1)
				(type default)
			)
			(layer "F.Fab")
		)
		(fp_line
			(start 0.12065 -0.2794)
			(end 0.12065 -0.3048)
			(stroke
				(width 0.1)
				(type default)
			)
			(layer "F.Fab")
		)
		(fp_line
			(start -0.12065 -0.2794)
			(end 0.12065 -0.2794)
			(stroke
				(width 0.1)
				(type default)
			)
			(layer "F.Fab")
		)
		(fp_line
			(start 0.120396 0.2794)
			(end -0.12065 0.2794)
			(stroke
				(width 0.1)
				(type default)
			)
			(layer "F.Fab")
		)
		(fp_line
			(start -0.12065 0.2794)
			(end -0.12065 0.3048)
			(stroke
				(width 0.1)
				(type default)
			)
			(layer "F.Fab")
		)
		(fp_line
			(start 0.67945 0.3048)
			(end 0.120396 0.3048)
			(stroke
				(width 0.1)
				(type default)
			)
			(layer "F.Fab")
		)
		(fp_line
			(start 0.120396 0.3048)
			(end 0.120396 0.2794)
			(stroke
				(width 0.1)
				(type default)
			)
			(layer "F.Fab")
		)
		(fp_line
			(start -0.12065 0.3048)
			(end -0.67945 0.3048)
			(stroke
				(width 0.1)
				(type default)
			)
			(layer "F.Fab")
		)
		(fp_line
			(start -0.67945 0.3048)
			(end -0.67945 -0.305054)
			(stroke
				(width 0.1)
				(type default)
			)
			(layer "F.Fab")
		)
		(pad "1" smd rect
			(at -0.40005 0 270)
			(size 0.4572 0.508)
			(layers "F.Cu" "F.Mask" "F.Paste")
			(net "FM_BOARD_BMC_SKU_ID4")
		)
		(pad "2" smd rect
			(at 0.40005 0 270)
			(size 0.4572 0.508)
			(layers "F.Cu" "F.Mask" "F.Paste")
			(net "GND")
		)
	)
	(footprint ""
		(layer "F.Cu")
		(at 81.739486 -142.041372 180)
		(property "Reference" "R676"
			(at 0 0 180)
			(layer "F.SilkS")
			(hide yes)
			(effects
				(font
					(size 1.27 1.27)
				)
			)
		)
		(property "Value" ""
			(at 0 0 180)
			(layer "F.Fab")
			(effects
				(font
					(size 1.27 1.27)
				)
			)
		)
		(duplicate_pad_numbers_are_jumpers no)
		(fp_line
			(start 0.7874 0.4064)
			(end -0.7874 0.4064)
			(stroke
				(width 0.1524)
				(type default)
			)
			(layer "F.SilkS")
		)
		(fp_line
			(start 0.7874 -0.4064)
			(end 0.7874 0.4064)
			(stroke
				(width 0.1524)
				(type default)
			)
			(layer "F.SilkS")
		)
		(fp_line
			(start -0.7874 0.4064)
			(end -0.7874 -0.4064)
			(stroke
				(width 0.1524)
				(type default)
			)
			(layer "F.SilkS")
		)
		(fp_line
			(start -0.7874 -0.4064)
			(end 0.7874 -0.4064)
			(stroke
				(width 0.1524)
				(type default)
			)
			(layer "F.SilkS")
		)
		(fp_line
			(start 0.67945 0.3048)
			(end 0.120396 0.3048)
			(stroke
				(width 0.1)
				(type default)
			)
			(layer "F.Fab")
		)
		(fp_line
			(start 0.67945 -0.3048)
			(end 0.67945 0.3048)
			(stroke
				(width 0.1)
				(type default)
			)
			(layer "F.Fab")
		)
		(fp_line
			(start 0.12065 -0.2794)
			(end 0.12065 -0.3048)
			(stroke
				(width 0.1)
				(type default)
			)
			(layer "F.Fab")
		)
		(fp_line
			(start 0.12065 -0.3048)
			(end 0.67945 -0.3048)
			(stroke
				(width 0.1)
				(type default)
			)
			(layer "F.Fab")
		)
		(fp_line
			(start 0.120396 0.3048)
			(end 0.120396 0.2794)
			(stroke
				(width 0.1)
				(type default)
			)
			(layer "F.Fab")
		)
		(fp_line
			(start 0.120396 0.2794)
			(end -0.12065 0.2794)
			(stroke
				(width 0.1)
				(type default)
			)
			(layer "F.Fab")
		)
		(fp_line
			(start -0.12065 0.3048)
			(end -0.67945 0.3048)
			(stroke
				(width 0.1)
				(type default)
			)
			(layer "F.Fab")
		)
		(fp_line
			(start -0.12065 0.2794)
			(end -0.12065 0.3048)
			(stroke
				(width 0.1)
				(type default)
			)
			(layer "F.Fab")
		)
		(fp_line
			(start -0.12065 -0.2794)
			(end 0.12065 -0.2794)
			(stroke
				(width 0.1)
				(type default)
			)
			(layer "F.Fab")
		)
		(fp_line
			(start -0.12065 -0.305054)
			(end -0.12065 -0.2794)
			(stroke
				(width 0.1)
				(type default)
			)
			(layer "F.Fab")
		)
		(fp_line
			(start -0.67945 0.3048)
			(end -0.67945 -0.305054)
			(stroke
				(width 0.1)
				(type default)
			)
			(layer "F.Fab")
		)
		(fp_line
			(start -0.67945 -0.305054)
			(end -0.12065 -0.305054)
			(stroke
				(width 0.1)
				(type default)
			)
			(layer "F.Fab")
		)
		(pad "1" smd circle
			(at -0.40005 0 180)
			(size 0 0)
			(layers "F.Cu" "F.Mask" "F.Paste")
			(net "I3C_SPD_DDREFGH_CPU1_LVC1_R_SCL")
		)
		(pad "2" smd circle
			(at 0.40005 0 180)
			(size 0 0)
			(layers "F.Cu" "F.Mask" "F.Paste")
			(net "I3C_SPD_DDREFGH_CPU1_LVC1_SCL")
		)
	)
	(footprint ""
		(layer "F.Cu")
		(at 366.644428 -362.786422 -90)
		(property "Reference" "PU173"
			(at -3.372866 0.046482 0)
			(unlocked yes)
			(layer "F.SilkS")
			(effects
				(font
					(size 0.7874 0.5842)
					(thickness 0.1524)
				)
			)
		)
		(property "Value" ""
			(at 0 0 270)
			(layer "F.Fab")
			(effects
				(font
					(size 1.27 1.27)
				)
			)
		)
		(duplicate_pad_numbers_are_jumpers no)
		(fp_line
			(start -1.949958 1.610106)
			(end -1.949958 -1.610106)
			(stroke
				(width 0.1524)
				(type default)
			)
			(layer "F.SilkS")
		)
		(fp_line
			(start 1.105662 1.610106)
			(end -1.949958 1.610106)
			(stroke
				(width 0.1524)
				(type default)
			)
			(layer "F.SilkS")
		)
		(fp_line
			(start 1.949958 -1.560068)
			(end 1.949958 0.953008)
			(stroke
				(width 0.1524)
				(type default)
			)
			(layer "F.SilkS")
		)
		(fp_line
			(start -1.949958 -1.610106)
			(end 1.949958 -1.610106)
			(stroke
				(width 0.1524)
				(type default)
			)
			(layer "F.SilkS")
		)
		(fp_line
			(start -0.750062 1.560068)
			(end -0.750062 -1.560068)
			(stroke
				(width 0.1)
				(type default)
			)
			(layer "F.Fab")
		)
		(fp_line
			(start 0.750062 1.560068)
			(end -0.750062 1.560068)
			(stroke
				(width 0.1)
				(type default)
			)
			(layer "F.Fab")
		)
		(fp_line
			(start -0.750062 -1.560068)
			(end 0.750062 -1.560068)
			(stroke
				(width 0.1)
				(type default)
			)
			(layer "F.Fab")
		)
		(fp_line
			(start 0.750062 -1.560068)
			(end 0.750062 1.560068)
			(stroke
				(width 0.1)
				(type default)
			)
			(layer "F.Fab")
		)
		(pad "D" smd rect
			(at 1.100074 0 180)
			(size 1.016 1.4224)
			(layers "F.Cu" "F.Mask" "F.Paste")
			(net "FM_HBM_VPP_SEL_CPU0_D")
		)
		(pad "G" smd rect
			(at -1.100074 -0.94996 180)
			(size 1.016 1.4224)
			(layers "F.Cu" "F.Mask" "F.Paste")
			(net "FM_HBM2_HBM3_VPP_SEL")
		)
		(pad "S" smd rect
			(at -1.100074 0.94996 180)
			(size 1.016 1.4224)
			(layers "F.Cu" "F.Mask" "F.Paste")
			(net "SH_PVPP_HBM_CPU0_N")
		)
	)
	(footprint ""
		(layer "F.Cu")
		(at 168.338754 -408.517344 -90)
		(property "Reference" "C1546"
			(at 0 0 270)
			(layer "F.SilkS")
			(hide yes)
			(effects
				(font
					(size 1.27 1.27)
				)
			)
		)
		(property "Value" ""
			(at 0 0 270)
			(layer "F.Fab")
			(effects
				(font
					(size 1.27 1.27)
				)
			)
		)
		(duplicate_pad_numbers_are_jumpers no)
		(fp_line
			(start -0.299974 0.150114)
			(end -0.299974 -0.150114)
			(stroke
				(width 0.1)
				(type default)
			)
			(layer "F.Fab")
		)
		(fp_line
			(start 0.299974 0.150114)
			(end -0.299974 0.150114)
			(stroke
				(width 0.1)
				(type default)
			)
			(layer "F.Fab")
		)
		(fp_line
			(start -0.299974 -0.150114)
			(end 0.299974 -0.150114)
			(stroke
				(width 0.1)
				(type default)
			)
			(layer "F.Fab")
		)
		(fp_line
			(start 0.299974 -0.150114)
			(end 0.299974 0.150114)
			(stroke
				(width 0.1)
				(type default)
			)
			(layer "F.Fab")
		)
		(pad "1" smd rect
			(at -0.2667 0 270)
			(size 0.3048 0.381)
			(layers "F.Cu" "F.Mask" "F.Paste")
			(net "P5E_CPU1_PE3_TX_C_DN<0>")
		)
		(pad "2" smd rect
			(at 0.2667 0 270)
			(size 0.3048 0.381)
			(layers "F.Cu" "F.Mask" "F.Paste")
			(net "P5E_CPU1_PE3_TX_DN<0>")
		)
	)
	(footprint ""
		(layer "F.Cu")
		(at 10.873486 -92.687648 90)
		(property "Reference" "R3661"
			(at 0 0 90)
			(layer "F.SilkS")
			(hide yes)
			(effects
				(font
					(size 1.27 1.27)
				)
			)
		)
		(property "Value" ""
			(at 0 0 90)
			(layer "F.Fab")
			(effects
				(font
					(size 1.27 1.27)
				)
			)
		)
		(duplicate_pad_numbers_are_jumpers no)
		(fp_line
			(start 0.7874 -0.4064)
			(end 0.7874 0.4064)
			(stroke
				(width 0.1524)
				(type default)
			)
			(layer "F.SilkS")
		)
		(fp_line
			(start -0.7874 -0.4064)
			(end 0.7874 -0.4064)
			(stroke
				(width 0.1524)
				(type default)
			)
			(layer "F.SilkS")
		)
		(fp_line
			(start 0.7874 0.4064)
			(end -0.7874 0.4064)
			(stroke
				(width 0.1524)
				(type default)
			)
			(layer "F.SilkS")
		)
		(fp_line
			(start -0.7874 0.4064)
			(end -0.7874 -0.4064)
			(stroke
				(width 0.1524)
				(type default)
			)
			(layer "F.SilkS")
		)
		(fp_line
			(start -0.12065 -0.305054)
			(end -0.12065 -0.2794)
			(stroke
				(width 0.1)
				(type default)
			)
			(layer "F.Fab")
		)
		(fp_line
			(start -0.67945 -0.305054)
			(end -0.12065 -0.305054)
			(stroke
				(width 0.1)
				(type default)
			)
			(layer "F.Fab")
		)
		(fp_line
			(start 0.67945 -0.3048)
			(end 0.67945 0.3048)
			(stroke
				(width 0.1)
				(type default)
			)
			(layer "F.Fab")
		)
		(fp_line
			(start 0.12065 -0.3048)
			(end 0.67945 -0.3048)
			(stroke
				(width 0.1)
				(type default)
			)
			(layer "F.Fab")
		)
		(fp_line
			(start 0.12065 -0.2794)
			(end 0.12065 -0.3048)
			(stroke
				(width 0.1)
				(type default)
			)
			(layer "F.Fab")
		)
		(fp_line
			(start -0.12065 -0.2794)
			(end 0.12065 -0.2794)
			(stroke
				(width 0.1)
				(type default)
			)
			(layer "F.Fab")
		)
		(fp_line
			(start 0.120396 0.2794)
			(end -0.12065 0.2794)
			(stroke
				(width 0.1)
				(type default)
			)
			(layer "F.Fab")
		)
		(fp_line
			(start -0.12065 0.2794)
			(end -0.12065 0.3048)
			(stroke
				(width 0.1)
				(type default)
			)
			(layer "F.Fab")
		)
		(fp_line
			(start 0.67945 0.3048)
			(end 0.120396 0.3048)
			(stroke
				(width 0.1)
				(type default)
			)
			(layer "F.Fab")
		)
		(fp_line
			(start 0.120396 0.3048)
			(end 0.120396 0.2794)
			(stroke
				(width 0.1)
				(type default)
			)
			(layer "F.Fab")
		)
		(fp_line
			(start -0.12065 0.3048)
			(end -0.67945 0.3048)
			(stroke
				(width 0.1)
				(type default)
			)
			(layer "F.Fab")
		)
		(fp_line
			(start -0.67945 0.3048)
			(end -0.67945 -0.305054)
			(stroke
				(width 0.1)
				(type default)
			)
			(layer "F.Fab")
		)
		(pad "1" smd circle
			(at -0.40005 0 90)
			(size 0 0)
			(layers "F.Cu" "F.Mask" "F.Paste")
			(net "GND")
		)
		(pad "2" smd circle
			(at 0.40005 0 90)
			(size 0 0)
			(layers "F.Cu" "F.Mask" "F.Paste")
			(net "RST_USB_HUB_R_N")
		)
	)
	(footprint ""
		(layer "F.Cu")
		(at 19.37131 -180.522626 90)
		(property "Reference" "PC1281"
			(at 0 0 90)
			(layer "F.SilkS")
			(hide yes)
			(effects
				(font
					(size 1.27 1.27)
				)
			)
		)
		(property "Value" ""
			(at 0 0 90)
			(layer "F.Fab")
			(effects
				(font
					(size 1.27 1.27)
				)
			)
		)
		(duplicate_pad_numbers_are_jumpers no)
		(fp_line
			(start 1.524 -0.762)
			(end 1.524 0.762)
			(stroke
				(width 0.1524)
				(type default)
			)
			(layer "F.SilkS")
		)
		(fp_line
			(start -1.524 -0.762)
			(end 1.524 -0.762)
			(stroke
				(width 0.1524)
				(type default)
			)
			(layer "F.SilkS")
		)
		(fp_line
			(start 1.524 0.762)
			(end -1.524 0.762)
			(stroke
				(width 0.1524)
				(type default)
			)
			(layer "F.SilkS")
		)
		(fp_line
			(start -1.524 0.762)
			(end -1.524 -0.762)
			(stroke
				(width 0.1524)
				(type default)
			)
			(layer "F.SilkS")
		)
		(fp_line
			(start 1.1049 -0.724916)
			(end -1.1049 -0.724916)
			(stroke
				(width 0.1)
				(type default)
			)
			(layer "F.Fab")
		)
		(fp_line
			(start -1.1049 -0.724916)
			(end -1.1049 0.724916)
			(stroke
				(width 0.1)
				(type default)
			)
			(layer "F.Fab")
		)
		(fp_line
			(start 1.1049 0.724916)
			(end 1.1049 -0.724916)
			(stroke
				(width 0.1)
				(type default)
			)
			(layer "F.Fab")
		)
		(fp_line
			(start -1.1049 0.724916)
			(end 1.1049 0.724916)
			(stroke
				(width 0.1)
				(type default)
			)
			(layer "F.Fab")
		)
		(pad "1" smd rect
			(at -0.889 0 270)
			(size 1.016 1.27)
			(layers "F.Cu" "F.Mask" "F.Paste")
			(net "SW_P12V_PVCCINFAON_CPU1_FLT")
		)
		(pad "2" smd rect
			(at 0.889 0 270)
			(size 1.016 1.27)
			(layers "F.Cu" "F.Mask" "F.Paste")
			(net "GND")
		)
	)
	(footprint ""
		(layer "F.Cu")
		(at 355.247448 -247.715024 90)
		(property "Reference" "C979"
			(at 0 0 90)
			(layer "F.SilkS")
			(hide yes)
			(effects
				(font
					(size 1.27 1.27)
				)
			)
		)
		(property "Value" ""
			(at 0 0 90)
			(layer "F.Fab")
			(effects
				(font
					(size 1.27 1.27)
				)
			)
		)
		(duplicate_pad_numbers_are_jumpers no)
		(fp_line
			(start 0.7874 -0.4064)
			(end 0.7874 0.4064)
			(stroke
				(width 0.1524)
				(type default)
			)
			(layer "F.SilkS")
		)
		(fp_line
			(start -0.7874 -0.4064)
			(end 0.7874 -0.4064)
			(stroke
				(width 0.1524)
				(type default)
			)
			(layer "F.SilkS")
		)
		(fp_line
			(start 0.7874 0.4064)
			(end -0.7874 0.4064)
			(stroke
				(width 0.1524)
				(type default)
			)
			(layer "F.SilkS")
		)
		(fp_line
			(start -0.7874 0.4064)
			(end -0.7874 -0.4064)
			(stroke
				(width 0.1524)
				(type default)
			)
			(layer "F.SilkS")
		)
		(fp_line
			(start -0.12065 -0.305054)
			(end -0.12065 -0.2794)
			(stroke
				(width 0.1)
				(type default)
			)
			(layer "F.Fab")
		)
		(fp_line
			(start -0.67945 -0.305054)
			(end -0.12065 -0.305054)
			(stroke
				(width 0.1)
				(type default)
			)
			(layer "F.Fab")
		)
		(fp_line
			(start 0.67945 -0.3048)
			(end 0.67945 0.3048)
			(stroke
				(width 0.1)
				(type default)
			)
			(layer "F.Fab")
		)
		(fp_line
			(start 0.12065 -0.3048)
			(end 0.67945 -0.3048)
			(stroke
				(width 0.1)
				(type default)
			)
			(layer "F.Fab")
		)
		(fp_line
			(start 0.12065 -0.2794)
			(end 0.12065 -0.3048)
			(stroke
				(width 0.1)
				(type default)
			)
			(layer "F.Fab")
		)
		(fp_line
			(start -0.12065 -0.2794)
			(end 0.12065 -0.2794)
			(stroke
				(width 0.1)
				(type default)
			)
			(layer "F.Fab")
		)
		(fp_line
			(start 0.120396 0.2794)
			(end -0.12065 0.2794)
			(stroke
				(width 0.1)
				(type default)
			)
			(layer "F.Fab")
		)
		(fp_line
			(start -0.12065 0.2794)
			(end -0.12065 0.3048)
			(stroke
				(width 0.1)
				(type default)
			)
			(layer "F.Fab")
		)
		(fp_line
			(start 0.67945 0.3048)
			(end 0.120396 0.3048)
			(stroke
				(width 0.1)
				(type default)
			)
			(layer "F.Fab")
		)
		(fp_line
			(start 0.120396 0.3048)
			(end 0.120396 0.2794)
			(stroke
				(width 0.1)
				(type default)
			)
			(layer "F.Fab")
		)
		(fp_line
			(start -0.12065 0.3048)
			(end -0.67945 0.3048)
			(stroke
				(width 0.1)
				(type default)
			)
			(layer "F.Fab")
		)
		(fp_line
			(start -0.67945 0.3048)
			(end -0.67945 -0.305054)
			(stroke
				(width 0.1)
				(type default)
			)
			(layer "F.Fab")
		)
		(pad "1" smd circle
			(at -0.40005 0 90)
			(size 0 0)
			(layers "F.Cu" "F.Mask" "F.Paste")
			(net "PVCCIN_CPU0")
		)
		(pad "2" smd circle
			(at 0.40005 0 90)
			(size 0 0)
			(layers "F.Cu" "F.Mask" "F.Paste")
			(net "GND")
		)
	)
)
